FILE_TYPE = MACRO_DRAWING;
SET COLOR_WIRE YELLOW;
SET COLOR_PROP ORANGE;
SET COLOR_DOT WHITE;
SET COLOR_ARC YELLOW;
SET COLOR_BODY GREEN;
SET COLOR_NOTE PURPLE;
SET PROP_DISPLAY VALUE;
SET PAGE_NUMBER P151;
FORCEADD SN74AUC2G66DCTR..1
(-6375 5800);
FORCEPROP 1 LAST LOCATION U153
J 0
(-6529 6032);
DISPLAY 0.489362 (-6529 6032);
PAINT SKYBLUE (-6529 6032);
FORCEPROP 0 LAST $SEC 1
J 0
(-6525 6175);
DISPLAY 0.680851 (-6525 6175);
PAINT MONO (-6525 6175);
DISPLAY INVISIBLE (-6525 6175);
FORCEPROP 0 LAST CDS_SEC 1
J 0
(-6525 6175);
DISPLAY 1.021277 (-6525 6175);
DISPLAY INVISIBLE (-6525 6175);
FORCEPROP 0 LASTPIN (-6675 5875) $PN 1
J 2
(-6685 5885);
DISPLAY 0.489362 (-6685 5885);
PAINT MONO (-6685 5885);
FORCEPROP 0 LASTPIN (-6075 5825) $PN 2
J 0
(-6065 5835);
DISPLAY 0.489362 (-6065 5835);
PAINT MONO (-6065 5835);
FORCEPROP 0 LASTPIN (-6675 5825) $PN 7
J 2
(-6685 5835);
DISPLAY 0.489362 (-6685 5835);
PAINT MONO (-6685 5835);
FORCEPROP 0 LASTPIN (-6675 5775) $PN 5
J 2
(-6685 5785);
DISPLAY 0.489362 (-6685 5785);
PAINT MONO (-6685 5785);
FORCEPROP 0 LASTPIN (-6075 5775) $PN 6
J 0
(-6065 5785);
DISPLAY 0.489362 (-6065 5785);
PAINT MONO (-6065 5785);
FORCEPROP 0 LASTPIN (-6675 5725) $PN 3
J 2
(-6685 5735);
DISPLAY 0.489362 (-6685 5735);
PAINT MONO (-6685 5735);
FORCEPROP 0 LASTPIN (-6075 5725) $PN 4
J 0
(-6065 5735);
DISPLAY 0.489362 (-6065 5735);
PAINT MONO (-6065 5735);
FORCEPROP 0 LASTPIN (-6075 5875) $PN 8
J 0
(-6065 5885);
DISPLAY 0.489362 (-6065 5885);
PAINT MONO (-6065 5885);
FORCEPROP 2 LAST PART_TYPE SMLF
J 0
(-6525 6125);
DISPLAY 1.021277 (-6525 6125);
FORCEPROP 1 LAST MATERIAL IC
J 0
(-6529 5929);
DISPLAY 0.489362 (-6529 5929);
PAINT SKYBLUE (-6529 5929);
FORCEPROP 2 LAST VALUE SN74AUC2G66DCTR
J 0
(-6525 6075);
DISPLAY 0.489362 (-6525 6075);
PAINT SKYBLUE (-6525 6075);
FORCEPROP 1 LAST PART_NUMBER AL2G0066C00
J 0
(-6529 5978);
DISPLAY 0.489362 (-6529 5978);
PAINT SKYBLUE (-6529 5978);
FORCEPROP 1 LAST CDS_LMAN_SYM_OUTLINE -150,125,150,-125
J 0
(-6375 5800);
DISPLAY 0.468085 (-6375 5800);
PAINT GREEN (-6375 5800);
DISPLAY INVISIBLE (-6375 5800);
FORCEPROP 1 LAST NEEDS_NO_SIZE TRUE
J 0
(-6375 5800);
DISPLAY 0.723404 (-6375 5800);
PAINT GREEN (-6375 5800);
DISPLAY INVISIBLE (-6375 5800);
FORCEPROP 2 LAST CDS_LIB pure_quanta
J 0
(-6375 5800);
DISPLAY INVISIBLE (-6375 5800);
FORCEPROP 1 LAST PATH I1
J 0
(-6375 5800);
DISPLAY 0.723404 (-6375 5800);
PAINT GREEN (-6375 5800);
DISPLAY INVISIBLE (-6375 5800);
FORCEADD Q_RES..2
R 2
(-8200 5325);
FORCEPROP 1 LAST LOCATION R1646
J 2
(-8250 5475);
DISPLAY 0.489362 (-8250 5475);
PAINT SKYBLUE (-8250 5475);
FORCEPROP 0 LAST $SEC 1
J 0
(-8250 5525);
DISPLAY 0.680851 (-8250 5525);
PAINT MONO (-8250 5525);
DISPLAY INVISIBLE (-8250 5525);
FORCEPROP 0 LAST CDS_SEC 1
J 0
(-8250 5525);
DISPLAY 1.021277 (-8250 5525);
DISPLAY INVISIBLE (-8250 5525);
FORCEPROP 1 LASTPIN (-8200 5425) $PN 1
J 2
(-8205 5387);
DISPLAY 0.489362 (-8205 5387);
PAINT MONO (-8205 5387);
FORCEPROP 1 LASTPIN (-8200 5225) $PN 2
J 2
(-8205 5235);
DISPLAY 0.489362 (-8205 5235);
PAINT MONO (-8205 5235);
FORCEPROP 1 LAST WATTAGE 1/16W
J 2
(-8250 5325);
DISPLAY 0.489362 (-8250 5325);
PAINT SKYBLUE (-8250 5325);
FORCEPROP 1 LAST MATERIAL CHIP
J 2
(-8250 5275);
DISPLAY 0.489362 (-8250 5275);
PAINT SKYBLUE (-8250 5275);
FORCEPROP 1 LAST TOLERANCE 1%
J 2
(-8250 5375);
DISPLAY 0.489362 (-8250 5375);
PAINT SKYBLUE (-8250 5375);
FORCEPROP 1 LAST VALUE 1K
J 2
(-8250 5425);
DISPLAY 0.489362 (-8250 5425);
PAINT SKYBLUE (-8250 5425);
FORCEPROP 1 LAST PART_NUMBER TMP_QCS21002FB24
J 2
(-8250 5175);
DISPLAY 0.489362 (-8250 5175);
PAINT SKYBLUE (-8250 5175);
FORCEPROP 1 LAST PACK_TYPE 0402LF
J 2
(-8250 5225);
DISPLAY 0.489362 (-8250 5225);
PAINT SKYBLUE (-8250 5225);
FORCEPROP 2 LAST CDS_LIB pure_quanta
J 2
(-8200 5325);
DISPLAY INVISIBLE (-8200 5325);
FORCEPROP 1 LAST PATH I10
J 2
(-8250 5500);
DISPLAY 0.978723 (-8250 5500);
PAINT WHITE (-8250 5500);
DISPLAY INVISIBLE (-8250 5500);
FORCEADD Q_RES..2
(-7600 5500);
FORCEPROP 1 LAST LOCATION R1647
J 0
(-7550 5650);
DISPLAY 0.489362 (-7550 5650);
PAINT SKYBLUE (-7550 5650);
FORCEPROP 0 LAST $SEC 1
J 0
(-7550 5700);
DISPLAY 0.680851 (-7550 5700);
PAINT MONO (-7550 5700);
DISPLAY INVISIBLE (-7550 5700);
FORCEPROP 0 LAST CDS_SEC 1
J 0
(-7550 5700);
DISPLAY 1.021277 (-7550 5700);
DISPLAY INVISIBLE (-7550 5700);
FORCEPROP 1 LASTPIN (-7600 5600) $PN 1
J 0
(-7595 5562);
DISPLAY 0.489362 (-7595 5562);
PAINT MONO (-7595 5562);
FORCEPROP 1 LASTPIN (-7600 5400) $PN 2
J 0
(-7595 5410);
DISPLAY 0.489362 (-7595 5410);
PAINT MONO (-7595 5410);
FORCEPROP 1 LAST WATTAGE 1/16W
J 0
(-7550 5500);
DISPLAY 0.489362 (-7550 5500);
PAINT SKYBLUE (-7550 5500);
FORCEPROP 1 LAST MATERIAL CHIP
J 0
(-7550 5450);
DISPLAY 0.489362 (-7550 5450);
PAINT SKYBLUE (-7550 5450);
FORCEPROP 1 LAST TOLERANCE 1%
J 0
(-7550 5550);
DISPLAY 0.489362 (-7550 5550);
PAINT SKYBLUE (-7550 5550);
FORCEPROP 1 LAST VALUE 1K
J 0
(-7550 5600);
DISPLAY 0.489362 (-7550 5600);
PAINT SKYBLUE (-7550 5600);
FORCEPROP 1 LAST PART_NUMBER TMP_QCS21002FB24
J 0
(-7550 5350);
DISPLAY 0.489362 (-7550 5350);
PAINT SKYBLUE (-7550 5350);
FORCEPROP 1 LAST PACK_TYPE 0402LF
J 0
(-7550 5400);
DISPLAY 0.489362 (-7550 5400);
PAINT SKYBLUE (-7550 5400);
FORCEPROP 2 LAST CDS_LIB pure_quanta
J 2
(-7600 5500);
DISPLAY INVISIBLE (-7600 5500);
FORCEPROP 1 LAST PATH I11
J 0
(-7550 5675);
DISPLAY 0.978723 (-7550 5675);
PAINT WHITE (-7550 5675);
DISPLAY INVISIBLE (-7550 5675);
FORCEADD UNIVERSAL_POWER..1
(-7600 5700);
FORCEPROP 3 LASTPIN (-7600 5650) SIG_NAME PVDD18_S5_P0\g
J 0
(-7590 5660);
DISPLAY 0.659574 (-7590 5660);
PAINT MONO (-7590 5660);
DISPLAY INVISIBLE (-7590 5660);
FORCEPROP 1 LAST HDL_POWER PVDD18_S5_P0
J 1
(-7600 5750);
DISPLAY 0.489362 (-7600 5750);
PAINT GREEN (-7600 5750);
FORCEPROP 2 LAST CDS_LIB pure_quanta_power
J 0
(-7600 5700);
DISPLAY INVISIBLE (-7600 5700);
FORCEPROP 1 LAST PATH I12
J 0
(-7550 5725);
DISPLAY 0.872340 (-7550 5725);
PAINT AQUA (-7550 5725);
DISPLAY INVISIBLE (-7550 5725);
FORCEADD GND..1
(-5975 5600);
FORCEPROP 3 LASTPIN (-5975 5650) SIG_NAME GND\g
J 0
(-5965 5660);
DISPLAY 0.659574 (-5965 5660);
PAINT MONO (-5965 5660);
DISPLAY INVISIBLE (-5965 5660);
FORCEPROP 2 LAST CDS_LIB pure_quanta_power
J 0
(-5975 5600);
DISPLAY INVISIBLE (-5975 5600);
FORCEPROP 1 LAST SIZE 1B
J 0
(-5900 5550);
DISPLAY 0.872340 (-5900 5550);
PAINT GREEN (-5900 5550);
DISPLAY INVISIBLE (-5900 5550);
FORCEPROP 1 LAST PATH I13
J 0
(-5900 5600);
DISPLAY 0.872340 (-5900 5600);
PAINT AQUA (-5900 5600);
DISPLAY INVISIBLE (-5900 5600);
FORCEPROP 1 LAST HDL_POWER GND
J 0
(-5975 5750);
DISPLAY 0.872340 (-5975 5750);
PAINT GREEN (-5975 5750);
DISPLAY INVISIBLE (-5975 5750);
FORCEADD GND..1
(-5725 5925);
FORCEPROP 3 LASTPIN (-5725 5975) SIG_NAME GND\g
J 0
(-5715 5985);
DISPLAY 0.659574 (-5715 5985);
PAINT MONO (-5715 5985);
DISPLAY INVISIBLE (-5715 5985);
FORCEPROP 2 LAST CDS_LIB pure_quanta_power
J 0
(-5725 5925);
DISPLAY INVISIBLE (-5725 5925);
FORCEPROP 1 LAST SIZE 1B
J 0
(-5650 5875);
DISPLAY 0.872340 (-5650 5875);
PAINT GREEN (-5650 5875);
DISPLAY INVISIBLE (-5650 5875);
FORCEPROP 1 LAST PATH I14
J 0
(-5650 5925);
DISPLAY 0.872340 (-5650 5925);
PAINT AQUA (-5650 5925);
DISPLAY INVISIBLE (-5650 5925);
FORCEPROP 1 LAST HDL_POWER GND
J 0
(-5725 6075);
DISPLAY 0.872340 (-5725 6075);
PAINT GREEN (-5725 6075);
DISPLAY INVISIBLE (-5725 6075);
FORCEADD Q_CAP..1
(-5725 6125);
FORCEPROP 1 LAST LOCATION C1519
J 0
(-5625 6275);
DISPLAY 0.489362 (-5625 6275);
PAINT SKYBLUE (-5625 6275);
FORCEPROP 2 LAST $SEC 1
J 0
(-5675 6325);
PAINT MONO (-5675 6325);
DISPLAY INVISIBLE (-5675 6325);
FORCEPROP 2 LAST CDS_SEC 1
J 0
(-5675 6325);
PAINT MONO (-5675 6325);
DISPLAY INVISIBLE (-5675 6325);
FORCEPROP 1 LASTPIN (-5725 6225) $PN 1
J 0
(-5715 6205);
DISPLAY 0.489362 (-5715 6205);
PAINT GREEN (-5715 6205);
FORCEPROP 1 LASTPIN (-5725 6025) $PN 2
J 0
(-5715 6005);
DISPLAY 0.489362 (-5715 6005);
PAINT GREEN (-5715 6005);
FORCEPROP 1 LAST MATERIAL X7R
J 0
(-5625 6075);
DISPLAY 0.489362 (-5625 6075);
PAINT SKYBLUE (-5625 6075);
FORCEPROP 1 LAST TOLERANCE 10%
J 0
(-5625 6125);
DISPLAY 0.489362 (-5625 6125);
PAINT SKYBLUE (-5625 6125);
FORCEPROP 1 LAST VALUE 0.1UF
J 0
(-5625 6225);
DISPLAY 0.489362 (-5625 6225);
PAINT SKYBLUE (-5625 6225);
FORCEPROP 1 LAST PART_NUMBER CH4103K1B08
J 0
(-5625 6025);
DISPLAY 0.489362 (-5625 6025);
PAINT SKYBLUE (-5625 6025);
FORCEPROP 1 LAST VOLTAGE 16V
J 0
(-5625 6175);
DISPLAY 0.489362 (-5625 6175);
PAINT SKYBLUE (-5625 6175);
FORCEPROP 1 LAST PACK_TYPE C0402
J 0
(-5625 5975);
DISPLAY 0.489362 (-5625 5975);
PAINT SKYBLUE (-5625 5975);
FORCEPROP 2 LAST CDS_LIB pure_quanta
J 0
(-5725 6125);
DISPLAY INVISIBLE (-5725 6125);
FORCEPROP 1 LAST PATH I15
J 0
(-5675 6275);
DISPLAY 0.978723 (-5675 6275);
PAINT WHITE (-5675 6275);
DISPLAY INVISIBLE (-5675 6275);
FORCEADD UNIVERSAL_POWER..1
(-5950 6400);
FORCEPROP 3 LASTPIN (-5950 6350) SIG_NAME PVDD18_S5_P0\g
J 0
(-5940 6360);
DISPLAY 0.659574 (-5940 6360);
PAINT MONO (-5940 6360);
DISPLAY INVISIBLE (-5940 6360);
FORCEPROP 1 LAST HDL_POWER PVDD18_S5_P0
J 1
(-5950 6450);
DISPLAY 0.489362 (-5950 6450);
PAINT GREEN (-5950 6450);
FORCEPROP 2 LAST CDS_LIB pure_quanta_power
J 0
(-5950 6400);
PAINT MONO (-5950 6400);
DISPLAY INVISIBLE (-5950 6400);
FORCEPROP 1 LAST PATH I16
J 0
(-5900 6425);
DISPLAY 0.872340 (-5900 6425);
PAINT AQUA (-5900 6425);
DISPLAY INVISIBLE (-5900 6425);
FORCEADD SN74AUC2G66DCTR..1
(-4975 4450);
FORCEPROP 1 LAST LOCATION U13
J 0
(-5129 4682);
DISPLAY 0.489362 (-5129 4682);
PAINT SKYBLUE (-5129 4682);
FORCEPROP 2 LAST SEC 1
J 0
(-5125 4825);
DISPLAY 0.680851 (-5125 4825);
PAINT MONO (-5125 4825);
DISPLAY INVISIBLE (-5125 4825);
FORCEPROP 2 LASTPIN (-5275 4525) $PN 1
J 2
(-5285 4535);
DISPLAY 0.489362 (-5285 4535);
PAINT MONO (-5285 4535);
FORCEPROP 2 LASTPIN (-4675 4475) $PN 2
J 0
(-4665 4485);
DISPLAY 0.489362 (-4665 4485);
PAINT MONO (-4665 4485);
FORCEPROP 2 LASTPIN (-5275 4475) $PN 7
J 2
(-5285 4485);
DISPLAY 0.489362 (-5285 4485);
PAINT MONO (-5285 4485);
FORCEPROP 2 LASTPIN (-5275 4425) $PN 5
J 2
(-5285 4435);
DISPLAY 0.489362 (-5285 4435);
PAINT MONO (-5285 4435);
FORCEPROP 2 LASTPIN (-4675 4425) $PN 6
J 0
(-4665 4435);
DISPLAY 0.489362 (-4665 4435);
PAINT MONO (-4665 4435);
FORCEPROP 2 LASTPIN (-5275 4375) $PN 3
J 2
(-5285 4385);
DISPLAY 0.489362 (-5285 4385);
PAINT MONO (-5285 4385);
FORCEPROP 2 LASTPIN (-4675 4375) $PN 4
J 0
(-4665 4385);
DISPLAY 0.489362 (-4665 4385);
PAINT MONO (-4665 4385);
FORCEPROP 2 LASTPIN (-4675 4525) $PN 8
J 0
(-4665 4535);
DISPLAY 0.489362 (-4665 4535);
PAINT MONO (-4665 4535);
FORCEPROP 2 LAST PART_TYPE SMLF
J 0
(-5125 4775);
DISPLAY 1.021277 (-5125 4775);
FORCEPROP 1 LAST MATERIAL IC
J 0
(-5129 4579);
DISPLAY 0.489362 (-5129 4579);
PAINT SKYBLUE (-5129 4579);
FORCEPROP 2 LAST VALUE SN74AUC2G66DCTR
J 0
(-5125 4725);
DISPLAY 0.489362 (-5125 4725);
PAINT SKYBLUE (-5125 4725);
FORCEPROP 1 LAST PART_NUMBER AL2G0066C00
J 0
(-5129 4628);
DISPLAY 0.489362 (-5129 4628);
PAINT SKYBLUE (-5129 4628);
FORCEPROP 2 LAST SEC_TYPE 
J 0
(-5125 4825);
DISPLAY 1.021277 (-5125 4825);
DISPLAY INVISIBLE (-5125 4825);
FORCEPROP 1 LAST NEEDS_NO_SIZE TRUE
J 0
(-4975 4450);
DISPLAY 0.723404 (-4975 4450);
PAINT GREEN (-4975 4450);
DISPLAY INVISIBLE (-4975 4450);
FORCEPROP 1 LAST CDS_LMAN_SYM_OUTLINE -150,125,150,-125
J 0
(-4975 4450);
DISPLAY 0.468085 (-4975 4450);
PAINT GREEN (-4975 4450);
DISPLAY INVISIBLE (-4975 4450);
FORCEPROP 2 LAST CDS_LIB pure_quanta
J 0
(-4975 4450);
DISPLAY INVISIBLE (-4975 4450);
FORCEPROP 1 LAST PATH I17
J 0
(-4975 4450);
DISPLAY 0.723404 (-4975 4450);
PAINT GREEN (-4975 4450);
DISPLAY INVISIBLE (-4975 4450);
FORCEADD OFFPAGE..1
(-6425 4525);
FORCEPROP 2 LAST $XR0 27 
J 0
(-6646 4525);
DISPLAY 0.638298 (-6646 4525);
PAINT MONO (-6646 4525);
FORCEPROP 2 LAST PATH I18
J 0
(-6675 4575);
DISPLAY 1.021277 (-6675 4575);
DISPLAY INVISIBLE (-6675 4575);
FORCEPROP 1 LAST COMMENT_BODY TRUE
J 0
(-6300 4425);
DISPLAY 0.872340 (-6300 4425);
PAINT GREEN (-6300 4425);
DISPLAY INVISIBLE (-6300 4425);
FORCEPROP 1 LAST OFFPAGE TRUE
J 0
(-6100 4400);
DISPLAY 0.872340 (-6100 4400);
PAINT GREEN (-6100 4400);
DISPLAY INVISIBLE (-6100 4400);
FORCEPROP 2 LAST CDS_LIB standard
J 0
(-6425 4525);
DISPLAY INVISIBLE (-6425 4525);
FORCEADD GND..1
(-7600 4650);
FORCEPROP 3 LASTPIN (-7600 4700) SIG_NAME GND\g
J 0
(-7590 4710);
DISPLAY 0.659574 (-7590 4710);
PAINT MONO (-7590 4710);
DISPLAY INVISIBLE (-7590 4710);
FORCEPROP 2 LAST CDS_LIB pure_quanta_power
J 0
(-7600 4650);
DISPLAY INVISIBLE (-7600 4650);
FORCEPROP 1 LAST SIZE 1B
J 0
(-7525 4600);
DISPLAY 0.872340 (-7525 4600);
PAINT GREEN (-7525 4600);
DISPLAY INVISIBLE (-7525 4600);
FORCEPROP 1 LAST PATH I19
J 0
(-7525 4650);
DISPLAY 0.872340 (-7525 4650);
PAINT AQUA (-7525 4650);
DISPLAY INVISIBLE (-7525 4650);
FORCEPROP 1 LAST HDL_POWER GND
J 0
(-7600 4800);
DISPLAY 0.872340 (-7600 4800);
PAINT GREEN (-7600 4800);
DISPLAY INVISIBLE (-7600 4800);
FORCEADD Q_RES..1
(-5225 5825);
FORCEPROP 1 LAST LOCATION R1648
J 0
(-5100 5825);
DISPLAY 0.489362 (-5100 5825);
PAINT SKYBLUE (-5100 5825);
FORCEPROP 0 LAST $SEC 1
J 0
(-5125 5875);
DISPLAY 0.680851 (-5125 5875);
PAINT MONO (-5125 5875);
DISPLAY INVISIBLE (-5125 5875);
FORCEPROP 0 LAST CDS_SEC 1
J 0
(-5125 5875);
DISPLAY 1.021277 (-5125 5875);
DISPLAY INVISIBLE (-5125 5875);
FORCEPROP 1 LASTPIN (-5325 5825) $PN 1
J 0
(-5313 5837);
DISPLAY 0.489362 (-5313 5837);
PAINT MONO (-5313 5837);
FORCEPROP 1 LASTPIN (-5125 5825) $PN 2
J 0
(-5163 5837);
DISPLAY 0.489362 (-5163 5837);
PAINT MONO (-5163 5837);
FORCEPROP 1 LAST MATERIAL CHIP
J 0
(-5400 5800);
DISPLAY 0.489362 (-5400 5800);
PAINT SKYBLUE (-5400 5800);
FORCEPROP 1 LAST TOLERANCE 1%
J 0
(-5125 5800);
DISPLAY 0.489362 (-5125 5800);
PAINT SKYBLUE (-5125 5800);
FORCEPROP 1 LAST VALUE 22
J 2
(-5325 5825);
DISPLAY 0.489362 (-5325 5825);
PAINT SKYBLUE (-5325 5825);
FORCEPROP 2 LAST CDS_LIB pure_quanta
J 0
(-5225 5825);
DISPLAY INVISIBLE (-5225 5825);
FORCEPROP 1 LAST PATH I2
J 0
(-5275 5975);
DISPLAY 0.978723 (-5275 5975);
PAINT WHITE (-5275 5975);
DISPLAY INVISIBLE (-5275 5975);
FORCEPROP 1 LAST WATTAGE 1/16W
J 2
(-5250 5675);
DISPLAY 0.978723 (-5250 5675);
PAINT SKYBLUE (-5250 5675);
DISPLAY INVISIBLE (-5250 5675);
FORCEPROP 1 LAST PART_NUMBER CS02202FB12
J 0
(-5275 5925);
DISPLAY 0.978723 (-5275 5925);
PAINT SKYBLUE (-5275 5925);
DISPLAY INVISIBLE (-5275 5925);
FORCEPROP 1 LAST PACK_TYPE 0402LF
J 0
(-4975 5675);
DISPLAY 0.978723 (-4975 5675);
PAINT SKYBLUE (-4975 5675);
DISPLAY INVISIBLE (-4975 5675);
FORCEADD UNIVERSAL_POWER..1
(-4225 5050);
FORCEPROP 3 LASTPIN (-4225 5000) SIG_NAME PVDD18_S5_P0\g
J 0
(-4215 5010);
DISPLAY 0.659574 (-4215 5010);
PAINT MONO (-4215 5010);
DISPLAY INVISIBLE (-4215 5010);
FORCEPROP 1 LAST HDL_POWER PVDD18_S5_P0
J 1
(-4225 5100);
DISPLAY 0.489362 (-4225 5100);
PAINT GREEN (-4225 5100);
FORCEPROP 2 LAST CDS_LIB pure_quanta_power
J 0
(-4225 5050);
PAINT MONO (-4225 5050);
DISPLAY INVISIBLE (-4225 5050);
FORCEPROP 1 LAST PATH I20
J 0
(-4175 5075);
DISPLAY 0.872340 (-4175 5075);
PAINT AQUA (-4175 5075);
DISPLAY INVISIBLE (-4175 5075);
FORCEADD GND..1
(-4000 4575);
FORCEPROP 3 LASTPIN (-4000 4625) SIG_NAME GND\g
J 0
(-3990 4635);
DISPLAY 0.659574 (-3990 4635);
PAINT MONO (-3990 4635);
DISPLAY INVISIBLE (-3990 4635);
FORCEPROP 2 LAST CDS_LIB pure_quanta_power
J 0
(-4000 4575);
DISPLAY INVISIBLE (-4000 4575);
FORCEPROP 1 LAST SIZE 1B
J 0
(-3925 4525);
DISPLAY 0.872340 (-3925 4525);
PAINT GREEN (-3925 4525);
DISPLAY INVISIBLE (-3925 4525);
FORCEPROP 1 LAST PATH I21
J 0
(-3925 4575);
DISPLAY 0.872340 (-3925 4575);
PAINT AQUA (-3925 4575);
DISPLAY INVISIBLE (-3925 4575);
FORCEPROP 1 LAST HDL_POWER GND
J 0
(-4000 4725);
DISPLAY 0.872340 (-4000 4725);
PAINT GREEN (-4000 4725);
DISPLAY INVISIBLE (-4000 4725);
FORCEADD Q_CAP..1
(-4000 4775);
FORCEPROP 1 LAST LOCATION C1521
J 0
(-3900 4925);
DISPLAY 0.489362 (-3900 4925);
PAINT SKYBLUE (-3900 4925);
FORCEPROP 2 LAST $SEC 1
J 0
(-3950 4975);
PAINT MONO (-3950 4975);
DISPLAY INVISIBLE (-3950 4975);
FORCEPROP 2 LAST CDS_SEC 1
J 0
(-3950 4975);
PAINT MONO (-3950 4975);
DISPLAY INVISIBLE (-3950 4975);
FORCEPROP 1 LASTPIN (-4000 4875) $PN 1
J 0
(-3990 4855);
DISPLAY 0.489362 (-3990 4855);
PAINT GREEN (-3990 4855);
FORCEPROP 1 LASTPIN (-4000 4675) $PN 2
J 0
(-3990 4655);
DISPLAY 0.489362 (-3990 4655);
PAINT GREEN (-3990 4655);
FORCEPROP 1 LAST MATERIAL X7R
J 0
(-3900 4725);
DISPLAY 0.489362 (-3900 4725);
PAINT SKYBLUE (-3900 4725);
FORCEPROP 1 LAST TOLERANCE 10%
J 0
(-3900 4775);
DISPLAY 0.489362 (-3900 4775);
PAINT SKYBLUE (-3900 4775);
FORCEPROP 1 LAST VALUE 0.1UF
J 0
(-3900 4875);
DISPLAY 0.489362 (-3900 4875);
PAINT SKYBLUE (-3900 4875);
FORCEPROP 1 LAST PART_NUMBER CH4103K1B08
J 0
(-3900 4675);
DISPLAY 0.489362 (-3900 4675);
PAINT SKYBLUE (-3900 4675);
FORCEPROP 1 LAST VOLTAGE 16V
J 0
(-3900 4825);
DISPLAY 0.489362 (-3900 4825);
PAINT SKYBLUE (-3900 4825);
FORCEPROP 1 LAST PACK_TYPE C0402
J 0
(-3900 4625);
DISPLAY 0.489362 (-3900 4625);
PAINT SKYBLUE (-3900 4625);
FORCEPROP 2 LAST CDS_LIB pure_quanta
J 0
(-4000 4775);
DISPLAY INVISIBLE (-4000 4775);
FORCEPROP 1 LAST PATH I22
J 0
(-3950 4925);
DISPLAY 0.978723 (-3950 4925);
PAINT WHITE (-3950 4925);
DISPLAY INVISIBLE (-3950 4925);
FORCEADD SN74AUC2G66DCTR..1
(-3125 4400);
FORCEPROP 1 LAST LOCATION U14
J 0
(-3279 4632);
DISPLAY 0.489362 (-3279 4632);
PAINT SKYBLUE (-3279 4632);
FORCEPROP 2 LAST SEC 1
J 0
(-3275 4775);
DISPLAY 0.680851 (-3275 4775);
PAINT MONO (-3275 4775);
DISPLAY INVISIBLE (-3275 4775);
FORCEPROP 2 LASTPIN (-3425 4475) $PN 1
J 2
(-3435 4485);
DISPLAY 0.489362 (-3435 4485);
PAINT MONO (-3435 4485);
FORCEPROP 2 LASTPIN (-2825 4425) $PN 2
J 0
(-2815 4435);
DISPLAY 0.489362 (-2815 4435);
PAINT MONO (-2815 4435);
FORCEPROP 2 LASTPIN (-3425 4425) $PN 7
J 2
(-3435 4435);
DISPLAY 0.489362 (-3435 4435);
PAINT MONO (-3435 4435);
FORCEPROP 2 LASTPIN (-3425 4375) $PN 5
J 2
(-3435 4385);
DISPLAY 0.489362 (-3435 4385);
PAINT MONO (-3435 4385);
FORCEPROP 2 LASTPIN (-2825 4375) $PN 6
J 0
(-2815 4385);
DISPLAY 0.489362 (-2815 4385);
PAINT MONO (-2815 4385);
FORCEPROP 2 LASTPIN (-3425 4325) $PN 3
J 2
(-3435 4335);
DISPLAY 0.489362 (-3435 4335);
PAINT MONO (-3435 4335);
FORCEPROP 2 LASTPIN (-2825 4325) $PN 4
J 0
(-2815 4335);
DISPLAY 0.489362 (-2815 4335);
PAINT MONO (-2815 4335);
FORCEPROP 2 LASTPIN (-2825 4475) $PN 8
J 0
(-2815 4485);
DISPLAY 0.489362 (-2815 4485);
PAINT MONO (-2815 4485);
FORCEPROP 2 LAST PART_TYPE SMLF
J 0
(-3275 4725);
DISPLAY 1.021277 (-3275 4725);
FORCEPROP 1 LAST MATERIAL IC
J 0
(-3279 4529);
DISPLAY 0.489362 (-3279 4529);
PAINT SKYBLUE (-3279 4529);
FORCEPROP 2 LAST VALUE SN74AUC2G66DCTR
J 0
(-3275 4675);
DISPLAY 0.489362 (-3275 4675);
PAINT SKYBLUE (-3275 4675);
FORCEPROP 1 LAST PART_NUMBER AL2G0066C00
J 0
(-3279 4578);
DISPLAY 0.489362 (-3279 4578);
PAINT SKYBLUE (-3279 4578);
FORCEPROP 2 LAST SEC_TYPE 
J 0
(-3275 4775);
DISPLAY 1.021277 (-3275 4775);
DISPLAY INVISIBLE (-3275 4775);
FORCEPROP 1 LAST CDS_LMAN_SYM_OUTLINE -150,125,150,-125
J 0
(-3125 4400);
DISPLAY 0.468085 (-3125 4400);
PAINT GREEN (-3125 4400);
DISPLAY INVISIBLE (-3125 4400);
FORCEPROP 1 LAST NEEDS_NO_SIZE TRUE
J 0
(-3125 4400);
DISPLAY 0.723404 (-3125 4400);
PAINT GREEN (-3125 4400);
DISPLAY INVISIBLE (-3125 4400);
FORCEPROP 2 LAST CDS_LIB pure_quanta
J 0
(-3125 4400);
DISPLAY INVISIBLE (-3125 4400);
FORCEPROP 1 LAST PATH I23
J 0
(-3125 4400);
DISPLAY 0.723404 (-3125 4400);
PAINT GREEN (-3125 4400);
DISPLAY INVISIBLE (-3125 4400);
FORCEADD Q_RES..2
R 2
(-5225 3400);
FORCEPROP 1 LAST LOCATION R1649
J 2
(-5275 3550);
DISPLAY 0.489362 (-5275 3550);
PAINT SKYBLUE (-5275 3550);
FORCEPROP 0 LAST $SEC 1
J 0
(-5275 3600);
DISPLAY 0.680851 (-5275 3600);
PAINT MONO (-5275 3600);
DISPLAY INVISIBLE (-5275 3600);
FORCEPROP 0 LAST CDS_SEC 1
J 0
(-5275 3600);
DISPLAY 1.021277 (-5275 3600);
DISPLAY INVISIBLE (-5275 3600);
FORCEPROP 1 LASTPIN (-5225 3500) $PN 1
J 2
(-5230 3462);
DISPLAY 0.489362 (-5230 3462);
PAINT MONO (-5230 3462);
FORCEPROP 1 LASTPIN (-5225 3300) $PN 2
J 2
(-5230 3310);
DISPLAY 0.489362 (-5230 3310);
PAINT MONO (-5230 3310);
FORCEPROP 1 LAST WATTAGE 1/16W
J 2
(-5275 3400);
DISPLAY 0.489362 (-5275 3400);
PAINT SKYBLUE (-5275 3400);
FORCEPROP 1 LAST MATERIAL CHIP
J 2
(-5275 3350);
DISPLAY 0.489362 (-5275 3350);
PAINT SKYBLUE (-5275 3350);
FORCEPROP 1 LAST TOLERANCE 1%
J 2
(-5275 3450);
DISPLAY 0.489362 (-5275 3450);
PAINT SKYBLUE (-5275 3450);
FORCEPROP 1 LAST VALUE 1K
J 2
(-5275 3500);
DISPLAY 0.489362 (-5275 3500);
PAINT SKYBLUE (-5275 3500);
FORCEPROP 1 LAST PART_NUMBER TMP_QCS21002FB24
J 2
(-5275 3250);
DISPLAY 0.489362 (-5275 3250);
PAINT SKYBLUE (-5275 3250);
FORCEPROP 1 LAST PACK_TYPE 0402LF
J 2
(-5275 3300);
DISPLAY 0.489362 (-5275 3300);
PAINT SKYBLUE (-5275 3300);
FORCEPROP 2 LAST CDS_LIB pure_quanta
J 2
(-5225 3400);
DISPLAY INVISIBLE (-5225 3400);
FORCEPROP 1 LAST PATH I25
J 2
(-5275 3575);
DISPLAY 0.978723 (-5275 3575);
PAINT WHITE (-5275 3575);
DISPLAY INVISIBLE (-5275 3575);
FORCEADD UNIVERSAL_POWER..1
(-4550 3725);
FORCEPROP 3 LASTPIN (-4550 3675) SIG_NAME PVDD18_S5_P0\g
J 0
(-4540 3685);
DISPLAY 0.659574 (-4540 3685);
PAINT MONO (-4540 3685);
DISPLAY INVISIBLE (-4540 3685);
FORCEPROP 1 LAST HDL_POWER PVDD18_S5_P0
J 1
(-4550 3775);
DISPLAY 0.489362 (-4550 3775);
PAINT GREEN (-4550 3775);
FORCEPROP 2 LAST CDS_LIB pure_quanta_power
J 0
(-4550 3725);
DISPLAY INVISIBLE (-4550 3725);
FORCEPROP 1 LAST PATH I26
J 0
(-4500 3750);
DISPLAY 0.872340 (-4500 3750);
PAINT AQUA (-4500 3750);
DISPLAY INVISIBLE (-4500 3750);
FORCEADD Q_RES..2
(-4550 3525);
FORCEPROP 1 LAST LOCATION R1650
J 0
(-4500 3675);
DISPLAY 0.489362 (-4500 3675);
PAINT SKYBLUE (-4500 3675);
FORCEPROP 0 LAST $SEC 1
J 0
(-4500 3725);
DISPLAY 0.680851 (-4500 3725);
PAINT MONO (-4500 3725);
DISPLAY INVISIBLE (-4500 3725);
FORCEPROP 0 LAST CDS_SEC 1
J 0
(-4500 3725);
DISPLAY 1.021277 (-4500 3725);
DISPLAY INVISIBLE (-4500 3725);
FORCEPROP 1 LASTPIN (-4550 3625) $PN 1
J 0
(-4545 3587);
DISPLAY 0.489362 (-4545 3587);
PAINT MONO (-4545 3587);
FORCEPROP 1 LASTPIN (-4550 3425) $PN 2
J 0
(-4545 3435);
DISPLAY 0.489362 (-4545 3435);
PAINT MONO (-4545 3435);
FORCEPROP 1 LAST WATTAGE 1/16W
J 0
(-4500 3525);
DISPLAY 0.489362 (-4500 3525);
PAINT SKYBLUE (-4500 3525);
FORCEPROP 1 LAST MATERIAL CHIP
J 0
(-4500 3475);
DISPLAY 0.489362 (-4500 3475);
PAINT SKYBLUE (-4500 3475);
FORCEPROP 1 LAST TOLERANCE 1%
J 0
(-4500 3575);
DISPLAY 0.489362 (-4500 3575);
PAINT SKYBLUE (-4500 3575);
FORCEPROP 1 LAST VALUE 1K
J 0
(-4500 3625);
DISPLAY 0.489362 (-4500 3625);
PAINT SKYBLUE (-4500 3625);
FORCEPROP 1 LAST PART_NUMBER TMP_QCS21002FB24
J 0
(-4500 3375);
DISPLAY 0.489362 (-4500 3375);
PAINT SKYBLUE (-4500 3375);
FORCEPROP 1 LAST PACK_TYPE 0402LF
J 0
(-4500 3425);
DISPLAY 0.489362 (-4500 3425);
PAINT SKYBLUE (-4500 3425);
FORCEPROP 2 LAST CDS_LIB pure_quanta
J 2
(-4550 3525);
DISPLAY INVISIBLE (-4550 3525);
FORCEPROP 1 LAST PATH I27
J 0
(-4500 3700);
DISPLAY 0.978723 (-4500 3700);
PAINT WHITE (-4500 3700);
DISPLAY INVISIBLE (-4500 3700);
FORCEADD UNIVERSAL_POWER..1
(-5225 3650);
FORCEPROP 3 LASTPIN (-5225 3600) SIG_NAME PVDD18_S5_P0\g
J 0
(-5215 3610);
DISPLAY 0.659574 (-5215 3610);
PAINT MONO (-5215 3610);
DISPLAY INVISIBLE (-5215 3610);
FORCEPROP 1 LAST HDL_POWER PVDD18_S5_P0
J 1
(-5225 3700);
DISPLAY 0.489362 (-5225 3700);
PAINT GREEN (-5225 3700);
FORCEPROP 2 LAST CDS_LIB pure_quanta_power
J 0
(-5225 3650);
PAINT MONO (-5225 3650);
DISPLAY INVISIBLE (-5225 3650);
FORCEPROP 1 LAST PATH I28
J 0
(-5175 3675);
DISPLAY 0.872340 (-5175 3675);
PAINT AQUA (-5175 3675);
DISPLAY INVISIBLE (-5175 3675);
FORCEADD GND..1
(-4550 2725);
FORCEPROP 3 LASTPIN (-4550 2775) SIG_NAME GND\g
J 0
(-4540 2785);
DISPLAY 0.659574 (-4540 2785);
PAINT MONO (-4540 2785);
DISPLAY INVISIBLE (-4540 2785);
FORCEPROP 2 LAST CDS_LIB pure_quanta_power
J 0
(-4550 2725);
DISPLAY INVISIBLE (-4550 2725);
FORCEPROP 1 LAST SIZE 1B
J 0
(-4475 2675);
DISPLAY 0.872340 (-4475 2675);
PAINT GREEN (-4475 2675);
DISPLAY INVISIBLE (-4475 2675);
FORCEPROP 1 LAST PATH I29
J 0
(-4475 2725);
DISPLAY 0.872340 (-4475 2725);
PAINT AQUA (-4475 2725);
DISPLAY INVISIBLE (-4475 2725);
FORCEPROP 1 LAST HDL_POWER GND
J 0
(-4550 2875);
DISPLAY 0.872340 (-4550 2875);
PAINT GREEN (-4550 2875);
DISPLAY INVISIBLE (-4550 2875);
FORCEADD GND..1
(-4900 5325);
FORCEPROP 3 LASTPIN (-4900 5375) SIG_NAME GND\g
J 0
(-4890 5385);
DISPLAY 0.659574 (-4890 5385);
PAINT MONO (-4890 5385);
DISPLAY INVISIBLE (-4890 5385);
FORCEPROP 1 LAST SIZE 1B
J 0
(-4825 5275);
DISPLAY 0.872340 (-4825 5275);
PAINT GREEN (-4825 5275);
DISPLAY INVISIBLE (-4825 5275);
FORCEPROP 2 LAST CDS_LIB pure_quanta_power
J 0
(-4900 5325);
DISPLAY INVISIBLE (-4900 5325);
FORCEPROP 1 LAST PATH I3
J 0
(-4825 5325);
DISPLAY 0.872340 (-4825 5325);
PAINT AQUA (-4825 5325);
DISPLAY INVISIBLE (-4825 5325);
FORCEPROP 1 LAST HDL_POWER GND
J 0
(-4900 5475);
DISPLAY 0.872340 (-4900 5475);
PAINT GREEN (-4900 5475);
DISPLAY INVISIBLE (-4900 5475);
FORCEADD OFFPAGE..1
(-6125 3050);
FORCEPROP 2 LAST $XR0 80 
J 0
(-6376 3050);
DISPLAY 0.638298 (-6376 3050);
PAINT MONO (-6376 3050);
FORCEPROP 2 LAST CDS_LIB standard
J 0
(-6125 3050);
DISPLAY INVISIBLE (-6125 3050);
FORCEPROP 1 LAST OFFPAGE TRUE
J 0
(-5800 2925);
DISPLAY 0.872340 (-5800 2925);
PAINT GREEN (-5800 2925);
DISPLAY INVISIBLE (-5800 2925);
FORCEPROP 1 LAST COMMENT_BODY TRUE
J 0
(-6000 2950);
DISPLAY 0.872340 (-6000 2950);
PAINT GREEN (-6000 2950);
DISPLAY INVISIBLE (-6000 2950);
FORCEPROP 2 LAST PATH I30
J 0
(-6375 3100);
DISPLAY 1.021277 (-6375 3100);
DISPLAY INVISIBLE (-6375 3100);
FORCEADD SN74AUC2G66DCTR..1
(-1850 3400);
FORCEPROP 1 LAST LOCATION U154
J 0
(-2004 3632);
DISPLAY 0.489362 (-2004 3632);
PAINT SKYBLUE (-2004 3632);
FORCEPROP 0 LAST $SEC 1
J 0
(-2000 3775);
DISPLAY 0.680851 (-2000 3775);
PAINT MONO (-2000 3775);
DISPLAY INVISIBLE (-2000 3775);
FORCEPROP 0 LAST CDS_SEC 1
J 0
(-2000 3775);
DISPLAY 1.021277 (-2000 3775);
DISPLAY INVISIBLE (-2000 3775);
FORCEPROP 0 LASTPIN (-2150 3475) $PN 1
J 2
(-2160 3485);
DISPLAY 0.489362 (-2160 3485);
PAINT MONO (-2160 3485);
FORCEPROP 0 LASTPIN (-1550 3425) $PN 2
J 0
(-1540 3435);
DISPLAY 0.489362 (-1540 3435);
PAINT MONO (-1540 3435);
FORCEPROP 0 LASTPIN (-2150 3425) $PN 7
J 2
(-2160 3435);
DISPLAY 0.489362 (-2160 3435);
PAINT MONO (-2160 3435);
FORCEPROP 0 LASTPIN (-2150 3375) $PN 5
J 2
(-2160 3385);
DISPLAY 0.489362 (-2160 3385);
PAINT MONO (-2160 3385);
FORCEPROP 0 LASTPIN (-1550 3375) $PN 6
J 0
(-1540 3385);
DISPLAY 0.489362 (-1540 3385);
PAINT MONO (-1540 3385);
FORCEPROP 0 LASTPIN (-2150 3325) $PN 3
J 2
(-2160 3335);
DISPLAY 0.489362 (-2160 3335);
PAINT MONO (-2160 3335);
FORCEPROP 0 LASTPIN (-1550 3325) $PN 4
J 0
(-1540 3335);
DISPLAY 0.489362 (-1540 3335);
PAINT MONO (-1540 3335);
FORCEPROP 0 LASTPIN (-1550 3475) $PN 8
J 0
(-1540 3485);
DISPLAY 0.489362 (-1540 3485);
PAINT MONO (-1540 3485);
FORCEPROP 2 LAST PART_TYPE SMLF
J 0
(-2000 3725);
DISPLAY 1.021277 (-2000 3725);
FORCEPROP 1 LAST MATERIAL IC
J 0
(-2004 3529);
DISPLAY 0.489362 (-2004 3529);
PAINT SKYBLUE (-2004 3529);
FORCEPROP 2 LAST VALUE SN74AUC2G66DCTR
J 0
(-2000 3675);
DISPLAY 0.489362 (-2000 3675);
PAINT SKYBLUE (-2000 3675);
FORCEPROP 1 LAST PART_NUMBER AL2G0066C00
J 0
(-2004 3578);
DISPLAY 0.489362 (-2004 3578);
PAINT SKYBLUE (-2004 3578);
FORCEPROP 1 LAST NEEDS_NO_SIZE TRUE
J 0
(-1850 3400);
DISPLAY 0.723404 (-1850 3400);
PAINT GREEN (-1850 3400);
DISPLAY INVISIBLE (-1850 3400);
FORCEPROP 1 LAST CDS_LMAN_SYM_OUTLINE -150,125,150,-125
J 0
(-1850 3400);
DISPLAY 0.468085 (-1850 3400);
PAINT GREEN (-1850 3400);
DISPLAY INVISIBLE (-1850 3400);
FORCEPROP 2 LAST CDS_LIB pure_quanta
J 0
(-1850 3400);
DISPLAY INVISIBLE (-1850 3400);
FORCEPROP 1 LAST PATH I31
J 0
(-1850 3400);
DISPLAY 0.723404 (-1850 3400);
PAINT GREEN (-1850 3400);
DISPLAY INVISIBLE (-1850 3400);
FORCEADD OFFPAGE..1
(-3075 3475);
FORCEPROP 2 LAST $XR0 54 
J 0
(-3326 3475);
DISPLAY 0.638298 (-3326 3475);
PAINT MONO (-3326 3475);
FORCEPROP 2 LAST PATH I32
J 0
(-3325 3525);
DISPLAY 1.021277 (-3325 3525);
DISPLAY INVISIBLE (-3325 3525);
FORCEPROP 1 LAST COMMENT_BODY TRUE
J 0
(-2950 3375);
DISPLAY 0.872340 (-2950 3375);
PAINT GREEN (-2950 3375);
DISPLAY INVISIBLE (-2950 3375);
FORCEPROP 1 LAST OFFPAGE TRUE
J 0
(-2750 3350);
DISPLAY 0.872340 (-2750 3350);
PAINT GREEN (-2750 3350);
DISPLAY INVISIBLE (-2750 3350);
FORCEPROP 2 LAST CDS_LIB standard
J 0
(-3075 3475);
DISPLAY INVISIBLE (-3075 3475);
FORCEADD OFFPAGE..2
(-1000 4425);
FORCEPROP 2 LAST $XR0 54 
J 0
(-811 4425);
DISPLAY 0.638298 (-811 4425);
PAINT MONO (-811 4425);
FORCEPROP 2 LAST PATH I33
J 0
(-800 4475);
DISPLAY 1.021277 (-800 4475);
DISPLAY INVISIBLE (-800 4475);
FORCEPROP 1 LAST COMMENT_BODY TRUE
J 0
(-1045 4330);
DISPLAY 0.872340 (-1045 4330);
PAINT GREEN (-1045 4330);
DISPLAY INVISIBLE (-1045 4330);
FORCEPROP 1 LAST OFFPAGE TRUE
J 0
(-675 4300);
DISPLAY 0.872340 (-675 4300);
PAINT GREEN (-675 4300);
DISPLAY INVISIBLE (-675 4300);
FORCEPROP 2 LAST CDS_LIB standard
J 0
(-1000 4425);
PAINT MONO (-1000 4425);
DISPLAY INVISIBLE (-1000 4425);
FORCEADD Q_RES..1
(-1975 4425);
FORCEPROP 1 LAST LOCATION R1651
J 0
(-1875 4425);
DISPLAY 0.489362 (-1875 4425);
PAINT SKYBLUE (-1875 4425);
FORCEPROP 0 LAST $SEC 1
J 0
(-1875 4475);
DISPLAY 0.680851 (-1875 4475);
PAINT MONO (-1875 4475);
DISPLAY INVISIBLE (-1875 4475);
FORCEPROP 0 LAST CDS_SEC 1
J 0
(-1875 4475);
DISPLAY 1.021277 (-1875 4475);
DISPLAY INVISIBLE (-1875 4475);
FORCEPROP 1 LASTPIN (-2075 4425) $PN 1
J 0
(-2063 4437);
DISPLAY 0.489362 (-2063 4437);
PAINT MONO (-2063 4437);
FORCEPROP 1 LASTPIN (-1875 4425) $PN 2
J 0
(-1913 4437);
DISPLAY 0.489362 (-1913 4437);
PAINT MONO (-1913 4437);
FORCEPROP 1 LAST MATERIAL CHIP
J 0
(-2150 4400);
DISPLAY 0.489362 (-2150 4400);
PAINT SKYBLUE (-2150 4400);
FORCEPROP 1 LAST TOLERANCE 1%
J 0
(-1875 4400);
DISPLAY 0.489362 (-1875 4400);
PAINT SKYBLUE (-1875 4400);
FORCEPROP 1 LAST VALUE 22
J 2
(-2075 4425);
DISPLAY 0.489362 (-2075 4425);
PAINT SKYBLUE (-2075 4425);
FORCEPROP 2 LAST CDS_LIB pure_quanta
J 0
(-1975 4425);
DISPLAY INVISIBLE (-1975 4425);
FORCEPROP 1 LAST PATH I34
J 0
(-2025 4575);
DISPLAY 0.978723 (-2025 4575);
PAINT WHITE (-2025 4575);
DISPLAY INVISIBLE (-2025 4575);
FORCEPROP 1 LAST WATTAGE 1/16W
J 2
(-2000 4275);
DISPLAY 0.978723 (-2000 4275);
PAINT SKYBLUE (-2000 4275);
DISPLAY INVISIBLE (-2000 4275);
FORCEPROP 1 LAST PART_NUMBER CS02202FB12
J 0
(-2025 4525);
DISPLAY 0.978723 (-2025 4525);
PAINT SKYBLUE (-2025 4525);
DISPLAY INVISIBLE (-2025 4525);
FORCEPROP 1 LAST PACK_TYPE 0402LF
J 0
(-1725 4275);
DISPLAY 0.978723 (-1725 4275);
PAINT SKYBLUE (-1725 4275);
DISPLAY INVISIBLE (-1725 4275);
FORCEADD UNIVERSAL_POWER..1
(-2375 5000);
FORCEPROP 3 LASTPIN (-2375 4950) SIG_NAME PVDD18_S5_P0\g
J 0
(-2365 4960);
DISPLAY 0.659574 (-2365 4960);
PAINT MONO (-2365 4960);
DISPLAY INVISIBLE (-2365 4960);
FORCEPROP 1 LAST HDL_POWER PVDD18_S5_P0
J 1
(-2375 5050);
DISPLAY 0.489362 (-2375 5050);
PAINT GREEN (-2375 5050);
FORCEPROP 2 LAST CDS_LIB pure_quanta_power
J 0
(-2375 5000);
PAINT MONO (-2375 5000);
DISPLAY INVISIBLE (-2375 5000);
FORCEPROP 1 LAST PATH I35
J 0
(-2325 5025);
DISPLAY 0.872340 (-2325 5025);
PAINT AQUA (-2325 5025);
DISPLAY INVISIBLE (-2325 5025);
FORCEADD Q_CAP..1
(-2150 4725);
FORCEPROP 1 LAST LOCATION C1522
J 0
(-2050 4875);
DISPLAY 0.489362 (-2050 4875);
PAINT SKYBLUE (-2050 4875);
FORCEPROP 2 LAST $SEC 1
J 0
(-2100 4925);
PAINT MONO (-2100 4925);
DISPLAY INVISIBLE (-2100 4925);
FORCEPROP 2 LAST CDS_SEC 1
J 0
(-2100 4925);
PAINT MONO (-2100 4925);
DISPLAY INVISIBLE (-2100 4925);
FORCEPROP 1 LASTPIN (-2150 4825) $PN 1
J 0
(-2140 4805);
DISPLAY 0.489362 (-2140 4805);
PAINT GREEN (-2140 4805);
FORCEPROP 1 LASTPIN (-2150 4625) $PN 2
J 0
(-2140 4605);
DISPLAY 0.489362 (-2140 4605);
PAINT GREEN (-2140 4605);
FORCEPROP 1 LAST MATERIAL X7R
J 0
(-2050 4675);
DISPLAY 0.489362 (-2050 4675);
PAINT SKYBLUE (-2050 4675);
FORCEPROP 1 LAST TOLERANCE 10%
J 0
(-2050 4725);
DISPLAY 0.489362 (-2050 4725);
PAINT SKYBLUE (-2050 4725);
FORCEPROP 1 LAST VALUE 0.1UF
J 0
(-2050 4825);
DISPLAY 0.489362 (-2050 4825);
PAINT SKYBLUE (-2050 4825);
FORCEPROP 1 LAST PART_NUMBER CH4103K1B08
J 0
(-2050 4625);
DISPLAY 0.489362 (-2050 4625);
PAINT SKYBLUE (-2050 4625);
FORCEPROP 1 LAST VOLTAGE 16V
J 0
(-2050 4775);
DISPLAY 0.489362 (-2050 4775);
PAINT SKYBLUE (-2050 4775);
FORCEPROP 1 LAST PACK_TYPE C0402
J 0
(-2050 4575);
DISPLAY 0.489362 (-2050 4575);
PAINT SKYBLUE (-2050 4575);
FORCEPROP 2 LAST CDS_LIB pure_quanta
J 0
(-2150 4725);
DISPLAY INVISIBLE (-2150 4725);
FORCEPROP 1 LAST PATH I36
J 0
(-2100 4875);
DISPLAY 0.978723 (-2100 4875);
PAINT WHITE (-2100 4875);
DISPLAY INVISIBLE (-2100 4875);
FORCEADD GND..1
(-2150 4525);
FORCEPROP 3 LASTPIN (-2150 4575) SIG_NAME GND\g
J 0
(-2140 4585);
DISPLAY 0.659574 (-2140 4585);
PAINT MONO (-2140 4585);
DISPLAY INVISIBLE (-2140 4585);
FORCEPROP 1 LAST SIZE 1B
J 0
(-2075 4475);
DISPLAY 0.872340 (-2075 4475);
PAINT GREEN (-2075 4475);
DISPLAY INVISIBLE (-2075 4475);
FORCEPROP 2 LAST CDS_LIB pure_quanta_power
J 0
(-2150 4525);
DISPLAY INVISIBLE (-2150 4525);
FORCEPROP 1 LAST PATH I37
J 0
(-2075 4525);
DISPLAY 0.872340 (-2075 4525);
PAINT AQUA (-2075 4525);
DISPLAY INVISIBLE (-2075 4525);
FORCEPROP 1 LAST HDL_POWER GND
J 0
(-2150 4675);
DISPLAY 0.872340 (-2150 4675);
PAINT GREEN (-2150 4675);
DISPLAY INVISIBLE (-2150 4675);
FORCEADD GND..1
(-4575 4250);
FORCEPROP 3 LASTPIN (-4575 4300) SIG_NAME GND\g
J 0
(-4565 4310);
DISPLAY 0.659574 (-4565 4310);
PAINT MONO (-4565 4310);
DISPLAY INVISIBLE (-4565 4310);
FORCEPROP 2 LAST CDS_LIB pure_quanta_power
J 0
(-4575 4250);
DISPLAY INVISIBLE (-4575 4250);
FORCEPROP 1 LAST SIZE 1B
J 0
(-4500 4200);
DISPLAY 0.872340 (-4500 4200);
PAINT GREEN (-4500 4200);
DISPLAY INVISIBLE (-4500 4200);
FORCEPROP 1 LAST PATH I38
J 0
(-4500 4250);
DISPLAY 0.872340 (-4500 4250);
PAINT AQUA (-4500 4250);
DISPLAY INVISIBLE (-4500 4250);
FORCEPROP 1 LAST HDL_POWER GND
J 0
(-4575 4400);
DISPLAY 0.872340 (-4575 4400);
PAINT GREEN (-4575 4400);
DISPLAY INVISIBLE (-4575 4400);
FORCEADD GND..1
(-2725 4200);
FORCEPROP 3 LASTPIN (-2725 4250) SIG_NAME GND\g
J 0
(-2715 4260);
DISPLAY 0.659574 (-2715 4260);
PAINT MONO (-2715 4260);
DISPLAY INVISIBLE (-2715 4260);
FORCEPROP 2 LAST CDS_LIB pure_quanta_power
J 0
(-2725 4200);
DISPLAY INVISIBLE (-2725 4200);
FORCEPROP 1 LAST SIZE 1B
J 0
(-2650 4150);
DISPLAY 0.872340 (-2650 4150);
PAINT GREEN (-2650 4150);
DISPLAY INVISIBLE (-2650 4150);
FORCEPROP 1 LAST PATH I39
J 0
(-2650 4200);
DISPLAY 0.872340 (-2650 4200);
PAINT AQUA (-2650 4200);
DISPLAY INVISIBLE (-2650 4200);
FORCEPROP 1 LAST HDL_POWER GND
J 0
(-2725 4350);
DISPLAY 0.872340 (-2725 4350);
PAINT GREEN (-2725 4350);
DISPLAY INVISIBLE (-2725 4350);
FORCEADD Q_CAP..1
(-4900 5625);
FORCEPROP 1 LAST LOCATION C1520
J 0
(-4850 5725);
DISPLAY 0.489362 (-4850 5725);
PAINT SKYBLUE (-4850 5725);
FORCEPROP 0 LAST $SEC 1
J 0
(-4850 5775);
PAINT MONO (-4850 5775);
DISPLAY INVISIBLE (-4850 5775);
FORCEPROP 0 LAST CDS_SEC 1
J 0
(-4850 5775);
PAINT MONO (-4850 5775);
DISPLAY INVISIBLE (-4850 5775);
FORCEPROP 1 LASTPIN (-4900 5725) $PN 1
J 0
(-4890 5705);
DISPLAY 0.489362 (-4890 5705);
PAINT GREEN (-4890 5705);
FORCEPROP 1 LASTPIN (-4900 5525) $PN 2
J 0
(-4890 5505);
DISPLAY 0.489362 (-4890 5505);
PAINT GREEN (-4890 5505);
FORCEPROP 1 LAST MATERIAL EMPTY
J 0
(-4850 5425);
DISPLAY 0.489362 (-4850 5425);
PAINT RED (-4850 5425);
FORCEPROP 1 LAST TOLERANCE 10%
J 0
(-4850 5575);
DISPLAY 0.489362 (-4850 5575);
PAINT SKYBLUE (-4850 5575);
FORCEPROP 1 LAST VALUE 0.01UF
J 0
(-4850 5675);
DISPLAY 0.489362 (-4850 5675);
PAINT SKYBLUE (-4850 5675);
FORCEPROP 1 LAST PART_NUMBER CH31006KB18
J 0
(-4850 5525);
DISPLAY 0.489362 (-4850 5525);
PAINT SKYBLUE (-4850 5525);
FORCEPROP 1 LAST VOLTAGE 50V
J 0
(-4850 5625);
DISPLAY 0.489362 (-4850 5625);
PAINT SKYBLUE (-4850 5625);
FORCEPROP 1 LAST PACK_TYPE C0402
J 0
(-4850 5475);
DISPLAY 0.489362 (-4850 5475);
PAINT SKYBLUE (-4850 5475);
FORCEPROP 2 LAST CDS_LIB pure_quanta
J 0
(-4900 5625);
PAINT MONO (-4900 5625);
DISPLAY INVISIBLE (-4900 5625);
FORCEPROP 1 LAST PATH I4
J 0
(-4850 5775);
DISPLAY 0.978723 (-4850 5775);
PAINT WHITE (-4850 5775);
DISPLAY INVISIBLE (-4850 5775);
FORCEADD GND..1
(-1450 3200);
FORCEPROP 3 LASTPIN (-1450 3250) SIG_NAME GND\g
J 0
(-1440 3260);
DISPLAY 0.659574 (-1440 3260);
PAINT MONO (-1440 3260);
DISPLAY INVISIBLE (-1440 3260);
FORCEPROP 1 LAST SIZE 1B
J 0
(-1375 3150);
DISPLAY 0.872340 (-1375 3150);
PAINT GREEN (-1375 3150);
DISPLAY INVISIBLE (-1375 3150);
FORCEPROP 2 LAST CDS_LIB pure_quanta_power
J 0
(-1450 3200);
DISPLAY INVISIBLE (-1450 3200);
FORCEPROP 1 LAST PATH I40
J 0
(-1375 3200);
DISPLAY 0.872340 (-1375 3200);
PAINT AQUA (-1375 3200);
DISPLAY INVISIBLE (-1375 3200);
FORCEPROP 1 LAST HDL_POWER GND
J 0
(-1450 3350);
DISPLAY 0.872340 (-1450 3350);
PAINT GREEN (-1450 3350);
DISPLAY INVISIBLE (-1450 3350);
FORCEADD OFFPAGE..2
(-475 3425);
FORCEPROP 2 LAST $XR0 150 
J 0
(-286 3425);
DISPLAY 0.638298 (-286 3425);
PAINT MONO (-286 3425);
FORCEPROP 2 LAST PATH I41
J 0
(-300 3500);
DISPLAY 1.021277 (-300 3500);
DISPLAY INVISIBLE (-300 3500);
FORCEPROP 1 LAST COMMENT_BODY TRUE
J 0
(-520 3330);
DISPLAY 0.872340 (-520 3330);
PAINT GREEN (-520 3330);
DISPLAY INVISIBLE (-520 3330);
FORCEPROP 1 LAST OFFPAGE TRUE
J 0
(-150 3300);
DISPLAY 0.872340 (-150 3300);
PAINT GREEN (-150 3300);
DISPLAY INVISIBLE (-150 3300);
FORCEPROP 2 LAST CDS_LIB standard
J 0
(-475 3425);
DISPLAY INVISIBLE (-475 3425);
FORCEADD Q_CAP..1
(-1000 3750);
FORCEPROP 1 LAST LOCATION C1523
J 0
(-900 3900);
DISPLAY 0.489362 (-900 3900);
PAINT SKYBLUE (-900 3900);
FORCEPROP 2 LAST $SEC 1
J 0
(-950 3950);
PAINT MONO (-950 3950);
DISPLAY INVISIBLE (-950 3950);
FORCEPROP 2 LAST CDS_SEC 1
J 0
(-950 3950);
PAINT MONO (-950 3950);
DISPLAY INVISIBLE (-950 3950);
FORCEPROP 1 LASTPIN (-1000 3850) $PN 1
J 0
(-990 3830);
DISPLAY 0.489362 (-990 3830);
PAINT GREEN (-990 3830);
FORCEPROP 1 LASTPIN (-1000 3650) $PN 2
J 0
(-990 3630);
DISPLAY 0.489362 (-990 3630);
PAINT GREEN (-990 3630);
FORCEPROP 1 LAST MATERIAL X7R
J 0
(-900 3700);
DISPLAY 0.489362 (-900 3700);
PAINT SKYBLUE (-900 3700);
FORCEPROP 1 LAST TOLERANCE 10%
J 0
(-900 3750);
DISPLAY 0.489362 (-900 3750);
PAINT SKYBLUE (-900 3750);
FORCEPROP 1 LAST VALUE 0.1UF
J 0
(-900 3850);
DISPLAY 0.489362 (-900 3850);
PAINT SKYBLUE (-900 3850);
FORCEPROP 1 LAST PART_NUMBER CH4103K1B08
J 0
(-900 3650);
DISPLAY 0.489362 (-900 3650);
PAINT SKYBLUE (-900 3650);
FORCEPROP 1 LAST VOLTAGE 16V
J 0
(-900 3800);
DISPLAY 0.489362 (-900 3800);
PAINT SKYBLUE (-900 3800);
FORCEPROP 1 LAST PACK_TYPE C0402
J 0
(-900 3600);
DISPLAY 0.489362 (-900 3600);
PAINT SKYBLUE (-900 3600);
FORCEPROP 2 LAST CDS_LIB pure_quanta
J 0
(-1000 3750);
DISPLAY INVISIBLE (-1000 3750);
FORCEPROP 1 LAST PATH I42
J 0
(-950 3900);
DISPLAY 0.978723 (-950 3900);
PAINT WHITE (-950 3900);
DISPLAY INVISIBLE (-950 3900);
FORCEADD GND..1
(-1000 3550);
FORCEPROP 3 LASTPIN (-1000 3600) SIG_NAME GND\g
J 0
(-990 3610);
DISPLAY 0.659574 (-990 3610);
PAINT MONO (-990 3610);
DISPLAY INVISIBLE (-990 3610);
FORCEPROP 2 LAST CDS_LIB pure_quanta_power
J 0
(-1000 3550);
DISPLAY INVISIBLE (-1000 3550);
FORCEPROP 1 LAST SIZE 1B
J 0
(-925 3500);
DISPLAY 0.872340 (-925 3500);
PAINT GREEN (-925 3500);
DISPLAY INVISIBLE (-925 3500);
FORCEPROP 1 LAST PATH I43
J 0
(-925 3550);
DISPLAY 0.872340 (-925 3550);
PAINT AQUA (-925 3550);
DISPLAY INVISIBLE (-925 3550);
FORCEPROP 1 LAST HDL_POWER GND
J 0
(-1000 3700);
DISPLAY 0.872340 (-1000 3700);
PAINT GREEN (-1000 3700);
DISPLAY INVISIBLE (-1000 3700);
FORCEADD UNIVERSAL_POWER..1
(-1225 4025);
FORCEPROP 3 LASTPIN (-1225 3975) SIG_NAME PVDD18_S5_P0\g
J 0
(-1215 3985);
DISPLAY 0.659574 (-1215 3985);
PAINT MONO (-1215 3985);
DISPLAY INVISIBLE (-1215 3985);
FORCEPROP 1 LAST HDL_POWER PVDD18_S5_P0
J 1
(-1225 4075);
DISPLAY 0.489362 (-1225 4075);
PAINT GREEN (-1225 4075);
FORCEPROP 2 LAST CDS_LIB pure_quanta_power
J 0
(-1225 4025);
PAINT MONO (-1225 4025);
DISPLAY INVISIBLE (-1225 4025);
FORCEPROP 1 LAST PATH I44
J 0
(-1175 4050);
DISPLAY 0.872340 (-1175 4050);
PAINT AQUA (-1175 4050);
DISPLAY INVISIBLE (-1175 4050);
FORCEADD MOSFET_N..1
(-7650 5075);
FORCEPROP 1 LAST LOCATION Q63
J 0
(-7500 4970);
DISPLAY 0.489362 (-7500 4970);
PAINT SKYBLUE (-7500 4970);
FORCEPROP 0 LAST $SEC 1
J 0
(-7500 5175);
DISPLAY 0.680851 (-7500 5175);
PAINT MONO (-7500 5175);
DISPLAY INVISIBLE (-7500 5175);
FORCEPROP 0 LAST CDS_SEC 1
J 0
(-7525 5275);
DISPLAY 1.021277 (-7525 5275);
DISPLAY INVISIBLE (-7525 5275);
FORCEPROP 1 LASTPIN (-7600 5175) $PN D
R 1
J 0
(-7600 5168);
DISPLAY 0.489362 (-7600 5168);
PAINT MONO (-7600 5168);
FORCEPROP 1 LASTPIN (-7750 4975) $PN G
J 2
(-7740 4978);
DISPLAY 0.489362 (-7740 4978);
PAINT MONO (-7740 4978);
FORCEPROP 1 LASTPIN (-7600 4875) $PN S
R 1
J 2
(-7600 4888);
DISPLAY 0.489362 (-7600 4888);
PAINT MONO (-7600 4888);
FORCEPROP 2 LAST PART_TYPE SMLF
J 0
(-7500 5125);
PAINT MONO (-7500 5125);
FORCEPROP 1 LAST MATERIAL IC
J 0
(-7500 4810);
DISPLAY 0.489362 (-7500 4810);
PAINT SKYBLUE (-7500 4810);
FORCEPROP 1 LAST VALUE BSS138K
J 0
(-7500 5050);
DISPLAY 0.489362 (-7500 5050);
PAINT SKYBLUE (-7500 5050);
FORCEPROP 1 LAST PART_NUMBER BAM138K0000
J 0
(-7500 4890);
DISPLAY 0.489362 (-7500 4890);
PAINT SKYBLUE (-7500 4890);
FORCEPROP 0 LAST MANUF_PN BSS138K
J 0
(-7525 5325);
DISPLAY 1.021277 (-7525 5325);
DISPLAY INVISIBLE (-7525 5325);
FORCEPROP 1 LAST CDS_LMAN_SYM_OUTLINE -50,50,100,-150
J 0
(-7650 5075);
DISPLAY 0.468085 (-7650 5075);
PAINT GREEN (-7650 5075);
DISPLAY INVISIBLE (-7650 5075);
FORCEPROP 2 LAST CDS_LIB pure_quanta
J 0
(-7650 5075);
DISPLAY INVISIBLE (-7650 5075);
FORCEPROP 0 LAST PATH I45
J 0
(-7525 5275);
DISPLAY 1.021277 (-7525 5275);
DISPLAY INVISIBLE (-7525 5275);
FORCEPROP 1 LAST PACK_TYPE SMLF
J 0
(-7625 4825);
DISPLAY 0.723404 (-7625 4825);
PAINT SKYBLUE (-7625 4825);
DISPLAY INVISIBLE (-7625 4825);
FORCEADD MOSFET_N..1
(-4600 3150);
FORCEPROP 1 LAST LOCATION Q64
J 0
(-4475 3060);
DISPLAY 0.489362 (-4475 3060);
PAINT SKYBLUE (-4475 3060);
FORCEPROP 0 LAST $SEC 1
J 0
(-4475 3250);
DISPLAY 0.680851 (-4475 3250);
PAINT MONO (-4475 3250);
DISPLAY INVISIBLE (-4475 3250);
FORCEPROP 0 LAST CDS_SEC 1
J 0
(-4475 3350);
DISPLAY 1.021277 (-4475 3350);
DISPLAY INVISIBLE (-4475 3350);
FORCEPROP 1 LASTPIN (-4550 3250) $PN D
R 1
J 0
(-4550 3243);
DISPLAY 0.489362 (-4550 3243);
PAINT MONO (-4550 3243);
FORCEPROP 1 LASTPIN (-4700 3050) $PN G
J 2
(-4690 3053);
DISPLAY 0.489362 (-4690 3053);
PAINT MONO (-4690 3053);
FORCEPROP 1 LASTPIN (-4550 2950) $PN S
R 1
J 2
(-4550 2963);
DISPLAY 0.489362 (-4550 2963);
PAINT MONO (-4550 2963);
FORCEPROP 2 LAST PART_TYPE SMLF
J 0
(-4475 3200);
PAINT MONO (-4475 3200);
FORCEPROP 1 LAST MATERIAL IC
J 0
(-4475 2900);
DISPLAY 0.489362 (-4475 2900);
PAINT SKYBLUE (-4475 2900);
FORCEPROP 1 LAST VALUE BSS138K
J 0
(-4475 3140);
DISPLAY 0.489362 (-4475 3140);
PAINT SKYBLUE (-4475 3140);
FORCEPROP 1 LAST PART_NUMBER BAM138K0000
J 0
(-4475 2980);
DISPLAY 0.489362 (-4475 2980);
PAINT SKYBLUE (-4475 2980);
FORCEPROP 0 LAST MANUF_PN BSS138K
J 0
(-4475 3400);
DISPLAY 1.021277 (-4475 3400);
DISPLAY INVISIBLE (-4475 3400);
FORCEPROP 2 LAST CDS_LIB pure_quanta
J 0
(-4600 3150);
DISPLAY INVISIBLE (-4600 3150);
FORCEPROP 1 LAST CDS_LMAN_SYM_OUTLINE -50,50,100,-150
J 0
(-4600 3150);
DISPLAY 0.468085 (-4600 3150);
PAINT GREEN (-4600 3150);
DISPLAY INVISIBLE (-4600 3150);
FORCEPROP 0 LAST PATH I46
J 0
(-4475 3350);
DISPLAY 1.021277 (-4475 3350);
DISPLAY INVISIBLE (-4475 3350);
FORCEPROP 1 LAST PACK_TYPE SMLF
J 0
(-4575 2900);
DISPLAY 0.723404 (-4575 2900);
PAINT SKYBLUE (-4575 2900);
DISPLAY INVISIBLE (-4575 2900);
FORCEADD OFFPAGE..1
(-8925 4975);
FORCEPROP 2 LAST $XR0 80 
J 0
(-9176 4975);
DISPLAY 0.638298 (-9176 4975);
PAINT MONO (-9176 4975);
FORCEPROP 2 LAST PATH I47
J 0
(-9175 5025);
DISPLAY 1.021277 (-9175 5025);
DISPLAY INVISIBLE (-9175 5025);
FORCEPROP 1 LAST COMMENT_BODY TRUE
J 0
(-8800 4875);
DISPLAY 0.872340 (-8800 4875);
PAINT GREEN (-8800 4875);
DISPLAY INVISIBLE (-8800 4875);
FORCEPROP 1 LAST OFFPAGE TRUE
J 0
(-8600 4850);
DISPLAY 0.872340 (-8600 4850);
PAINT GREEN (-8600 4850);
DISPLAY INVISIBLE (-8600 4850);
FORCEPROP 2 LAST CDS_LIB standard
J 0
(-8925 4975);
DISPLAY INVISIBLE (-8925 4975);
FORCEADD OFFPAGE..2
(-4250 5825);
FORCEPROP 2 LAST $XR0 27 
J 0
(-4061 5825);
DISPLAY 0.638298 (-4061 5825);
PAINT MONO (-4061 5825);
FORCEPROP 2 LAST PATH I5
J 0
(-4050 5875);
DISPLAY 1.021277 (-4050 5875);
DISPLAY INVISIBLE (-4050 5875);
FORCEPROP 1 LAST COMMENT_BODY TRUE
J 0
(-4295 5730);
DISPLAY 0.872340 (-4295 5730);
PAINT GREEN (-4295 5730);
DISPLAY INVISIBLE (-4295 5730);
FORCEPROP 1 LAST OFFPAGE TRUE
J 0
(-3925 5700);
DISPLAY 0.872340 (-3925 5700);
PAINT GREEN (-3925 5700);
DISPLAY INVISIBLE (-3925 5700);
FORCEPROP 2 LAST CDS_LIB standard
J 0
(-4250 5825);
PAINT MONO (-4250 5825);
DISPLAY INVISIBLE (-4250 5825);
FORCEADD OFFPAGE..1
(-7575 5875);
FORCEPROP 2 LAST $XR0 150 
J 0
(-7857 5875);
DISPLAY 0.638298 (-7857 5875);
PAINT MONO (-7857 5875);
FORCEPROP 2 LAST PATH I6
J 0
(-7525 5950);
DISPLAY 1.021277 (-7525 5950);
DISPLAY INVISIBLE (-7525 5950);
FORCEPROP 1 LAST COMMENT_BODY TRUE
J 0
(-7450 5775);
DISPLAY 0.872340 (-7450 5775);
PAINT GREEN (-7450 5775);
DISPLAY INVISIBLE (-7450 5775);
FORCEPROP 1 LAST OFFPAGE TRUE
J 0
(-7250 5750);
DISPLAY 0.872340 (-7250 5750);
PAINT GREEN (-7250 5750);
DISPLAY INVISIBLE (-7250 5750);
FORCEPROP 2 LAST CDS_LIB standard
J 0
(-7575 5875);
DISPLAY INVISIBLE (-7575 5875);
FORCEADD UNIVERSAL_POWER..1
(-8200 5575);
FORCEPROP 3 LASTPIN (-8200 5525) SIG_NAME PVDD18_S5_P0\g
J 0
(-8190 5535);
DISPLAY 0.659574 (-8190 5535);
PAINT MONO (-8190 5535);
DISPLAY INVISIBLE (-8190 5535);
FORCEPROP 1 LAST HDL_POWER PVDD18_S5_P0
J 1
(-8200 5625);
DISPLAY 0.489362 (-8200 5625);
PAINT GREEN (-8200 5625);
FORCEPROP 2 LAST CDS_LIB pure_quanta_power
J 0
(-8200 5575);
PAINT MONO (-8200 5575);
DISPLAY INVISIBLE (-8200 5575);
FORCEPROP 1 LAST PATH I9
J 0
(-8150 5600);
DISPLAY 0.872340 (-8150 5600);
PAINT AQUA (-8150 5600);
DISPLAY INVISIBLE (-8150 5600);
FORCEADD QUANTA_TITLE_BLOCK_C..1
(0 0);
FORCEPROP 0 LAST CDS_CON_LAST_MODIFIED Fri Mar 11 14:53:17 2022
J 0
(-1885 15);
DISPLAY INVISIBLE (-1885 15);
FORCEPROP 1 LAST CUSTOM_TXT_CDS <CON_LAST_MODIFIED>
J 0
(-1885 15);
DISPLAY 0.978723 (-1885 15);
FORCEPROP 2 LAST CUSTOM_TXT_CDS <XR_PAGE_TITLE>
J 0
(-7890 5250);
DISPLAY 0.638298 (-7890 5250);
PAINT PINK (-7890 5250);
DISPLAY INVISIBLE (-7890 5250);
FORCEPROP 1 LAST CUSTOM_TXT_CDS <NAME_2>
J 0
(-3175 50);
FORCEPROP 1 LAST CUSTOM_TXT_CDS <NAME_1>
J 0
(-3175 175);
FORCEPROP 1 LAST CUSTOM_TXT_CDS <Q_NUMBER>
J 0
(-1403 103);
DISPLAY 1.212766 (-1403 103);
FORCEPROP 1 LAST CUSTOM_TXT_CDS <Q_PROJ>
J 0
(-2382 102);
DISPLAY 1.212766 (-2382 102);
FORCEPROP 1 LAST CUSTOM_TXT_CDS <Q_REV>
J 0
(-184 103);
DISPLAY 1.212766 (-184 103);
FORCEPROP 1 LAST CUSTOM_TXT_CDS <CON_PAGE_NUM> OF <CON_TOTAL_PAGES>
J 0
(-446 18);
DISPLAY 0.978723 (-446 18);
FORCEPROP 1 LAST Q_DEPT BU9
J 1
(-3763 49);
DISPLAY 1.957447 (-3763 49);
PAINT GREEN (-3763 49);
FORCEPROP 1 LAST Q_TITLE JTAG - TDI/TDO
J 0
(-9300 50);
DISPLAY 2.446809 (-9300 50);
PAINT GREEN (-9300 50);
FORCEPROP 2 LAST PAGE_BORDER TRUE
J 0
(-7890 5250);
DISPLAY 0.638298 (-7890 5250);
PAINT PINK (-7890 5250);
DISPLAY INVISIBLE (-7890 5250);
FORCEPROP 1 LAST CDS_LMAN_SYM_OUTLINE -9475,6775,100,-125
J 0
(0 0);
DISPLAY 0.468085 (0 0);
PAINT GREEN (0 0);
DISPLAY INVISIBLE (0 0);
FORCEPROP 2 LAST CDS_LIB pure_quanta
J 0
(0 0);
DISPLAY INVISIBLE (0 0);
FORCEPROP 1 LAST COMMENT_BODY TRUE
J 0
(12 -13);
DISPLAY 0.978723 (12 -13);
PAINT GREEN (12 -13);
DISPLAY INVISIBLE (12 -13);
FORCEPROP 2 LAST CDS_XR_PAGE_TITLE CR-151 : @T6G_MB_LIB.T6G(SCH_1):PAGE151
J 0
(-7890 5250);
DISPLAY 0.638298 (-7890 5250);
PAINT PINK (-7890 5250);
DISPLAY INVISIBLE (-7890 5250);
FORCEADD DNS..1
(-4925 5600);
PAINT RED (-4925 5600);
FORCEPROP 2 LAST CDS_LIB mstr_misc
J 0
(-4925 5600);
DISPLAY INVISIBLE (-4925 5600);
FORCEPROP 1 LAST COMMENT_BODY TRUE
R 1
J 0
(-4850 5375);
DISPLAY 0.872340 (-4850 5375);
PAINT GREEN (-4850 5375);
DISPLAY INVISIBLE (-4850 5375);
WIRE 16 -1 (-7600 5650)(-7600 5600);
WIRE 16 -1 (-6075 5725)(-5975 5725);
WIRE 16 -1 (-5975 5725)(-5975 5650);
WIRE 16 -1 (-5725 6025)(-5725 5975);
WIRE 16 -1 (-7600 4875)(-7600 4700);
WIRE 16 -1 (-4000 4675)(-4000 4625);
WIRE 16 -1 (-4550 3675)(-4550 3625);
WIRE 16 -1 (-5225 3600)(-5225 3500);
WIRE 16 -1 (-4550 2950)(-4550 2775);
WIRE 16 -1 (-4900 5525)(-4900 5375);
WIRE 16 -1 (-2150 4625)(-2150 4575);
WIRE 16 -1 (-4575 4375)(-4575 4300);
WIRE 16 -1 (-4675 4375)(-4575 4375);
WIRE 16 -1 (-2725 4325)(-2725 4250);
WIRE 16 -1 (-2825 4325)(-2725 4325);
WIRE 16 -1 (-1450 3325)(-1450 3250);
WIRE 16 -1 (-1550 3325)(-1450 3325);
WIRE 16 -1 (-1000 3650)(-1000 3600);
WIRE 16 -1 (-8200 5525)(-8200 5425);
WIRE 16 -1 (-8875 4975)(-8200 4975);
FORCEPROP 2 LAST SIG_NAME CPU0_HDT_BYPASS_SEL
J 0
(-8710 4985);
DISPLAY 0.489362 (-8710 4985);
WIRE 16 -1 (-8200 4975)(-8025 4975);
WIRE 16 -1 (-8200 5225)(-8200 4975);
WIRE 16 -1 (-8025 5825)(-8025 4975);
WIRE 16 -1 (-8025 4975)(-7750 4975);
WIRE 16 -1 (-6950 5825)(-8025 5825);
WIRE 16 -1 (-6675 5825)(-6950 5825);
WIRE 16 -1 (-6950 5825)(-6950 4475);
WIRE 16 -1 (-6950 4475)(-5275 4475);
WIRE 16 -1 (-5225 3050)(-5050 3050);
WIRE 16 -1 (-5225 3300)(-5225 3050);
WIRE 16 -1 (-5225 3050)(-6075 3050);
FORCEPROP 2 LAST SIG_NAME CPU1_HDT_BYPASS_SEL
J 0
(-5875 3060);
DISPLAY 0.489362 (-5875 3060);
WIRE 16 -1 (-5050 3950)(-5050 3050);
WIRE 16 -1 (-5050 3050)(-4700 3050);
WIRE 16 -1 (-5050 3950)(-3650 3950);
WIRE 16 -1 (-3650 4425)(-3650 3950);
WIRE 16 -1 (-3650 3950)(-3650 3425);
WIRE 16 -1 (-3650 3425)(-2150 3425);
WIRE 16 -1 (-3650 4425)(-3425 4425);
WIRE 16 -1 (-6825 5725)(-6675 5725);
WIRE 16 -1 (-6825 5250)(-6825 5725);
WIRE 16 -1 (-6825 5250)(-6825 4375);
WIRE 16 -1 (-7600 5250)(-6825 5250);
FORCEPROP 2 LAST SIG_NAME FM_PLD_CPU0_PRSNT_HDT_N
J 0
(-7535 5260);
DISPLAY 0.489362 (-7535 5260);
FORCEPROP 2 LASTPROP $XRERR UNIQUE?
J 0
(-7775 5260);
DISPLAY 0.638298 (-7775 5260);
PAINT MONO (-7775 5260);
DISPLAY INVISIBLE (-7775 5260);
WIRE 16 -1 (-7600 5400)(-7600 5250);
WIRE 16 -1 (-7600 5250)(-7600 5175);
WIRE 16 -1 (-6825 4375)(-5275 4375);
WIRE 16 -1 (-7525 5875)(-6825 5875);
FORCEPROP 2 LAST SIG_NAME JTAG_CPUX_TDI
J 0
(-7335 5885);
DISPLAY 0.489362 (-7335 5885);
WIRE 16 -1 (-6825 5875)(-6675 5875);
WIRE 16 -1 (-6825 5875)(-6825 5775);
WIRE 16 -1 (-6825 5775)(-6675 5775);
WIRE 16 -1 (-6375 4525)(-5275 4525);
FORCEPROP 2 LAST SIG_NAME JTAG_CPU0_TDO
J 0
(-6185 4535);
DISPLAY 0.489362 (-6185 4535);
WIRE 16 -1 (-5450 5775)(-5450 4425);
WIRE 16 -1 (-6075 5775)(-5450 5775);
FORCEPROP 2 LAST SIG_NAME JTAG_CPU0_BYPASS
J 0
(-5935 5785);
DISPLAY 0.489362 (-5935 5785);
FORCEPROP 2 LASTPROP $XRERR UNIQUE?
J 0
(-6175 5785);
DISPLAY 0.638298 (-6175 5785);
PAINT MONO (-6175 5785);
DISPLAY INVISIBLE (-6175 5785);
WIRE 16 -1 (-5450 4425)(-5275 4425);
WIRE 16 -1 (-6075 5825)(-5325 5825);
FORCEPROP 2 LAST SIG_NAME JTAG_CPU0_R_TDI
J 0
(-5935 5835);
DISPLAY 0.489362 (-5935 5835);
FORCEPROP 2 LASTPROP $XRERR UNIQUE?
J 0
(-6175 5835);
DISPLAY 0.638298 (-6175 5835);
PAINT MONO (-6175 5835);
DISPLAY INVISIBLE (-6175 5835);
WIRE 16 -1 (-4225 4475)(-4225 4425);
FORCEPROP 2 LAST SIG_NAME JTAG_CPU0_TDO_CPU1_TDI
J 0
(-4335 4485);
DISPLAY 0.489362 (-4335 4485);
FORCEPROP 2 LASTPROP $XRERR UNIQUE?
J 0
(-4575 4485);
DISPLAY 0.638298 (-4575 4485);
PAINT MONO (-4575 4485);
DISPLAY INVISIBLE (-4575 4485);
WIRE 16 -1 (-4675 4475)(-4225 4475);
WIRE 16 -1 (-4225 4475)(-3825 4475);
WIRE 16 -1 (-4225 4425)(-4675 4425);
WIRE 16 -1 (-3825 4475)(-3425 4475);
WIRE 16 -1 (-3825 4475)(-3825 4375);
WIRE 16 -1 (-3825 4375)(-3425 4375);
WIRE 16 -1 (-4225 4525)(-4225 4950);
WIRE 16 -1 (-4225 4525)(-4675 4525);
WIRE 16 -1 (-4000 4950)(-4225 4950);
WIRE 16 -1 (-4225 5000)(-4225 4950);
WIRE 16 -1 (-4000 4875)(-4000 4950);
WIRE 16 -1 (-5125 5825)(-4900 5825);
WIRE 16 -1 (-4300 5825)(-4900 5825);
FORCEPROP 2 LAST SIG_NAME JTAG_CPU0_TDI
J 0
(-4785 5835);
DISPLAY 0.489362 (-4785 5835);
WIRE 16 -1 (-4900 5725)(-4900 5825);
WIRE 16 -1 (-6075 5875)(-5950 5875);
WIRE 16 -1 (-5950 5875)(-5950 6300);
WIRE 16 -1 (-5725 6300)(-5950 6300);
WIRE 16 -1 (-5950 6350)(-5950 6300);
WIRE 16 -1 (-5725 6225)(-5725 6300);
WIRE 16 -1 (-4550 3325)(-3825 3325);
WIRE 16 -1 (-4550 3425)(-4550 3325);
WIRE 16 -1 (-4550 3325)(-4550 3250);
WIRE 16 -1 (-3825 4325)(-3825 3325);
WIRE 16 -1 (-2150 3325)(-3825 3325);
FORCEPROP 2 LAST SIG_NAME FM_PLD_CPU1_PRSNT_HDT_N
J 0
(-3785 3335);
DISPLAY 0.489362 (-3785 3335);
FORCEPROP 2 LASTPROP $XRERR UNIQUE?
J 0
(-4025 3335);
DISPLAY 0.638298 (-4025 3335);
PAINT MONO (-4025 3335);
DISPLAY INVISIBLE (-4025 3335);
WIRE 16 -1 (-3825 4325)(-3425 4325);
WIRE 16 -1 (-3025 3475)(-2150 3475);
FORCEPROP 2 LAST SIG_NAME JTAG_CPU1_TDO
J 0
(-2835 3485);
DISPLAY 0.489362 (-2835 3485);
WIRE 16 -1 (-1100 3425)(-1100 3375);
WIRE 16 -1 (-1550 3425)(-1100 3425);
WIRE 16 -1 (-1100 3425)(-525 3425);
FORCEPROP 2 LAST SIG_NAME JTAG_CPUX_TDO
J 0
(-1035 3435);
DISPLAY 0.489362 (-1035 3435);
WIRE 16 -1 (-1100 3375)(-1550 3375);
WIRE 16 -1 (-1225 3475)(-1225 3925);
WIRE 16 -1 (-1225 3475)(-1550 3475);
WIRE 16 -1 (-1000 3925)(-1225 3925);
WIRE 16 -1 (-1225 3975)(-1225 3925);
WIRE 16 -1 (-1000 3850)(-1000 3925);
WIRE 16 -1 (-2225 4375)(-2225 3375);
WIRE 16 -1 (-2825 4375)(-2225 4375);
FORCEPROP 2 LAST SIG_NAME JTAG_CPU1_BYPASS
J 0
(-2685 4385);
DISPLAY 0.489362 (-2685 4385);
FORCEPROP 2 LASTPROP $XRERR UNIQUE?
J 0
(-2925 4385);
DISPLAY 0.638298 (-2925 4385);
PAINT MONO (-2925 4385);
DISPLAY INVISIBLE (-2925 4385);
WIRE 16 -1 (-2225 3375)(-2150 3375);
WIRE 16 -1 (-2825 4425)(-2075 4425);
FORCEPROP 2 LAST SIG_NAME JTAG_CPU1_R_TDI
J 0
(-2685 4435);
DISPLAY 0.489362 (-2685 4435);
FORCEPROP 2 LASTPROP $XRERR UNIQUE?
J 0
(-2925 4435);
DISPLAY 0.638298 (-2925 4435);
PAINT MONO (-2925 4435);
DISPLAY INVISIBLE (-2925 4435);
WIRE 16 -1 (-2375 4475)(-2375 4900);
WIRE 16 -1 (-2375 4475)(-2825 4475);
WIRE 16 -1 (-2150 4900)(-2375 4900);
WIRE 16 -1 (-2375 4950)(-2375 4900);
WIRE 16 -1 (-2150 4825)(-2150 4900);
WIRE 16 -1 (-1875 4425)(-1050 4425);
FORCEPROP 2 LAST SIG_NAME JTAG_CPU1_TDI
J 0
(-1535 4435);
DISPLAY 0.489362 (-1535 4435);
DOT 1 (-5225 3050);
DOT 1 (-8200 4975);
DOT 1 (-6825 5250);
DOT 1 (-4225 4950);
DOT 1 (-2375 4900);
DOT 1 (-3825 4475);
DOT 1 (-1225 3925);
DOT 1 (-1100 3425);
DOT 1 (-3650 3950);
DOT 1 (-3825 3325);
DOT 1 (-5950 6300);
DOT 1 (-4900 5825);
DOT 1 (-4225 4475);
DOT 1 (-6825 5875);
DOT 1 (-6950 5825);
DOT 1 (-7600 5250);
DOT 1 (-4550 3325);
DOT 1 (-5050 3050);
DOT 1 (-8025 4975);
FORCENOTE
L:BYPASS
(-6025 2625) 0;
DISPLAY LEFT (-6025 2625);
DISPLAY 2.510638 (-6025 2625);
PAINT WHITE (-6025 2625);
FORCENOTE
H:CPU0
(-8825 4750) 0;
DISPLAY LEFT (-8825 4750);
DISPLAY 2.510638 (-8825 4750);
PAINT WHITE (-8825 4750);
FORCENOTE
L:BYPASS
(-8825 4600) 0;
DISPLAY LEFT (-8825 4600);
DISPLAY 2.510638 (-8825 4600);
PAINT WHITE (-8825 4600);
FORCENOTE
CPU0 TDO
(-6575 4625) 0;
DISPLAY LEFT (-6575 4625);
DISPLAY 2.510638 (-6575 4625);
PAINT WHITE (-6575 4625);
FORCENOTE
CPU1 TDO
(-3225 3575) 0;
DISPLAY LEFT (-3225 3575);
DISPLAY 2.510638 (-3225 3575);
PAINT WHITE (-3225 3575);
FORCENOTE
CPU1 TDI
(-1575 4550) 0;
DISPLAY LEFT (-1575 4550);
DISPLAY 2.510638 (-1575 4550);
PAINT WHITE (-1575 4550);
FORCENOTE
CPU0 TDI
(-5000 5975) 0;
DISPLAY LEFT (-5000 5975);
DISPLAY 2.510638 (-5000 5975);
PAINT WHITE (-5000 5975);
FORCENOTE
H:CPU1
(-6025 2775) 0;
DISPLAY LEFT (-6025 2775);
DISPLAY 2.510638 (-6025 2775);
PAINT WHITE (-6025 2775);
QUIT
